# T6G (Grand Teton) — schematic netlist excerpt (pin names and nets, part order shuffled) for the footprints in the layout excerpt that follows; sources: Cadence DE-HDL packaged netlist, KiCad conversion of 04192023_DAF0TMB3IC0_F0TG_MB_C_brd_V02_OCP.brd

PR273  Q_RES  0 5% CHIP  pkg 0402LF  page 220 : A = PVDDCR_CPU1_P1_VOS5 ; B = PVDDCR_CPU1_P1
C2530  Q_CAP  22UF 4V 20% X6S  pkg C0402  page 70 : A = PVDDCR_SOC_P0 ; B = GND

(kicad_pcb
	(version 20260206)
	(generator "pcbnew")
	(generator_version "10.0")
	(general
		(thickness 1.6)
		(legacy_teardrops no)
	)
	(paper "A4")
	(title_block
		(title "04192023_DAF0TMB3IC0_F0TG_MB_C_brd_V02_OCP.brd")
		(comment 1 "Grand Teton / footprints 7260-7261 of 8354")
	)
	(layers
		(0 "F.Cu" signal "TOP")
		(4 "In1.Cu" signal "GND")
		(6 "In2.Cu" signal "IN1")
		(8 "In3.Cu" signal "GND1")
		(10 "In4.Cu" signal "IN2")
		(12 "In5.Cu" signal "GND2")
		(14 "In6.Cu" signal "IN3")
		(16 "In7.Cu" signal "GND3")
		(18 "In8.Cu" signal "VCC")
		(20 "In9.Cu" signal "VCC1")
		(22 "In10.Cu" signal "GND4")
		(24 "In11.Cu" signal "IN4")
		(26 "In12.Cu" signal "GND5")
		(28 "In13.Cu" signal "IN5")
		(30 "In14.Cu" signal "GND6")
		(32 "In15.Cu" signal "IN6")
		(34 "In16.Cu" signal "GND7")
		(2 "B.Cu" signal "BOTTOM")
		(9 "F.Adhes" user "F.Adhesive")
		(11 "B.Adhes" user "B.Adhesive")
		(13 "F.Paste" user "Package Geometry/Pastemask Top")
		(15 "B.Paste" user "Package Geometry/Pastemask Bottom")
		(5 "F.SilkS" user "Ref Des/Silkscreen Top")
		(7 "B.SilkS" user "Ref Des/Silkscreen Bottom")
		(1 "F.Mask" user "Board Geometry/Soldermask Top")
		(3 "B.Mask" user "Board Geometry/Soldermask Bottom")
		(17 "Dwgs.User" user "User.Drawings")
		(19 "Cmts.User" user "User.Comments")
		(21 "Eco1.User" user "User.Eco1")
		(23 "Eco2.User" user "User.Eco2")
		(25 "Edge.Cuts" user "Board Geometry/Outline")
		(27 "Margin" user)
		(31 "F.CrtYd" user "Package Geometry/Place Bound Top")
		(29 "B.CrtYd" user "Package Geometry/Place Bound Bottom")
		(35 "F.Fab" user "Ref Des/Assembly Top")
		(33 "B.Fab" user "Ref Des/Assembly Bottom")
	)
	(footprint ""
		(layer "B.Cu")
		(at 91.792044 -337.694524 -90)
		(property "Reference" "PR273"
			(at 0 0 90)
			(layer "B.SilkS")
			(hide yes)
			(effects
				(font
					(size 1.27 1.27)
				)
				(justify mirror)
			)
		)
		(property "Value" ""
			(at 0 0 90)
			(layer "B.Fab")
			(effects
				(font
					(size 1.27 1.27)
				)
				(justify mirror)
			)
		)
		(duplicate_pad_numbers_are_jumpers no)
		(fp_line
			(start -0.7874 0.4064)
			(end 0.7874 0.4064)
			(stroke
				(width 0.1524)
				(type default)
			)
			(layer "B.SilkS")
		)
		(fp_line
			(start 0.7874 0.4064)
			(end 0.7874 -0.4064)
			(stroke
				(width 0.1524)
				(type default)
			)
			(layer "B.SilkS")
		)
		(fp_line
			(start -0.7874 -0.4064)
			(end -0.7874 0.4064)
			(stroke
				(width 0.1524)
				(type default)
			)
			(layer "B.SilkS")
		)
		(fp_line
			(start 0.7874 -0.4064)
			(end -0.7874 -0.4064)
			(stroke
				(width 0.1524)
				(type default)
			)
			(layer "B.SilkS")
		)
		(fp_line
			(start -0.67945 0.3048)
			(end -0.120396 0.3048)
			(stroke
				(width 0.1)
				(type default)
			)
			(layer "B.Fab")
		)
		(fp_line
			(start -0.120396 0.3048)
			(end -0.120396 0.2794)
			(stroke
				(width 0.1)
				(type default)
			)
			(layer "B.Fab")
		)
		(fp_line
			(start 0.12065 0.3048)
			(end 0.67945 0.3048)
			(stroke
				(width 0.1)
				(type default)
			)
			(layer "B.Fab")
		)
		(fp_line
			(start 0.67945 0.3048)
			(end 0.67945 -0.305054)
			(stroke
				(width 0.1)
				(type default)
			)
			(layer "B.Fab")
		)
		(fp_line
			(start -0.120396 0.2794)
			(end 0.12065 0.2794)
			(stroke
				(width 0.1)
				(type default)
			)
			(layer "B.Fab")
		)
		(fp_line
			(start 0.12065 0.2794)
			(end 0.12065 0.3048)
			(stroke
				(width 0.1)
				(type default)
			)
			(layer "B.Fab")
		)
		(fp_line
			(start -0.12065 -0.2794)
			(end -0.12065 -0.3048)
			(stroke
				(width 0.1)
				(type default)
			)
			(layer "B.Fab")
		)
		(fp_line
			(start 0.12065 -0.2794)
			(end -0.12065 -0.2794)
			(stroke
				(width 0.1)
				(type default)
			)
			(layer "B.Fab")
		)
		(fp_line
			(start -0.67945 -0.3048)
			(end -0.67945 0.3048)
			(stroke
				(width 0.1)
				(type default)
			)
			(layer "B.Fab")
		)
		(fp_line
			(start -0.12065 -0.3048)
			(end -0.67945 -0.3048)
			(stroke
				(width 0.1)
				(type default)
			)
			(layer "B.Fab")
		)
		(fp_line
			(start 0.12065 -0.305054)
			(end 0.12065 -0.2794)
			(stroke
				(width 0.1)
				(type default)
			)
			(layer "B.Fab")
		)
		(fp_line
			(start 0.67945 -0.305054)
			(end 0.12065 -0.305054)
			(stroke
				(width 0.1)
				(type default)
			)
			(layer "B.Fab")
		)
		(pad "1" smd circle
			(at 0.40005 0 90)
			(size 0 0)
			(layers "B.Cu" "B.Mask" "B.Paste")
			(net "PVDDCR_CPU1_P1_VOS5")
		)
		(pad "2" smd circle
			(at -0.40005 0 90)
			(size 0 0)
			(layers "B.Cu" "B.Mask" "B.Paste")
			(net "PVDDCR_CPU1_P1")
		)
	)
	(footprint ""
		(layer "B.Cu")
		(at 371.551454 -257.930142)
		(property "Reference" "C2530"
			(at 0 0 0)
			(layer "B.SilkS")
			(hide yes)
			(effects
				(font
					(size 1.27 1.27)
				)
				(justify mirror)
			)
		)
		(property "Value" ""
			(at 0 0 0)
			(layer "B.Fab")
			(effects
				(font
					(size 1.27 1.27)
				)
				(justify mirror)
			)
		)
		(duplicate_pad_numbers_are_jumpers no)
		(fp_line
			(start -0.7874 -0.4064)
			(end -0.7874 0.4064)
			(stroke
				(width 0.1524)
				(type default)
			)
			(layer "B.SilkS")
		)
		(fp_line
			(start -0.7874 0.4064)
			(end 0.7874 0.4064)
			(stroke
				(width 0.1524)
				(type default)
			)
			(layer "B.SilkS")
		)
		(fp_line
			(start 0.7874 -0.4064)
			(end -0.7874 -0.4064)
			(stroke
				(width 0.1524)
				(type default)
			)
			(layer "B.SilkS")
		)
		(fp_line
			(start 0.7874 0.4064)
			(end 0.7874 -0.4064)
			(stroke
				(width 0.1524)
				(type default)
			)
			(layer "B.SilkS")
		)
		(fp_line
			(start -0.67945 -0.3048)
			(end -0.67945 0.3048)
			(stroke
				(width 0.1)
				(type default)
			)
			(layer "B.Fab")
		)
		(fp_line
			(start -0.67945 0.3048)
			(end -0.120396 0.3048)
			(stroke
				(width 0.1)
				(type default)
			)
			(layer "B.Fab")
		)
		(fp_line
			(start -0.12065 -0.3048)
			(end -0.67945 -0.3048)
			(stroke
				(width 0.1)
				(type default)
			)
			(layer "B.Fab")
		)
		(fp_line
			(start -0.12065 -0.2794)
			(end -0.12065 -0.3048)
			(stroke
				(width 0.1)
				(type default)
			)
			(layer "B.Fab")
		)
		(fp_line
			(start -0.120396 0.2794)
			(end 0.12065 0.2794)
			(stroke
				(width 0.1)
				(type default)
			)
			(layer "B.Fab")
		)
		(fp_line
			(start -0.120396 0.3048)
			(end -0.120396 0.2794)
			(stroke
				(width 0.1)
				(type default)
			)
			(layer "B.Fab")
		)
		(fp_line
			(start 0.12065 -0.305054)
			(end 0.12065 -0.2794)
			(stroke
				(width 0.1)
				(type default)
			)
			(layer "B.Fab")
		)
		(fp_line
			(start 0.12065 -0.2794)
			(end -0.12065 -0.2794)
			(stroke
				(width 0.1)
				(type default)
			)
			(layer "B.Fab")
		)
		(fp_line
			(start 0.12065 0.2794)
			(end 0.12065 0.3048)
			(stroke
				(width 0.1)
				(type default)
			)
			(layer "B.Fab")
		)
		(fp_line
			(start 0.12065 0.3048)
			(end 0.67945 0.3048)
			(stroke
				(width 0.1)
				(type default)
			)
			(layer "B.Fab")
		)
		(fp_line
			(start 0.67945 -0.305054)
			(end 0.12065 -0.305054)
			(stroke
				(width 0.1)
				(type default)
			)
			(layer "B.Fab")
		)
		(fp_line
			(start 0.67945 0.3048)
			(end 0.67945 -0.305054)
			(stroke
				(width 0.1)
				(type default)
			)
			(layer "B.Fab")
		)
		(pad "1" smd circle
			(at 0.40005 0 180)
			(size 0 0)
			(layers "B.Cu" "B.Mask" "B.Paste")
			(net "PVDDCR_SOC_P0")
		)
		(pad "2" smd circle
			(at -0.40005 0 180)
			(size 0 0)
			(layers "B.Cu" "B.Mask" "B.Paste")
			(net "GND")
		)
	)
)
